(kicad_pcb
	(version 20241229)
	(generator "pcbnew")
	(generator_version "9.0")
	(general
		(thickness 1.552)
		(legacy_teardrops no)
	)
	(paper "A4")
	(title_block
		(date "2023-07-25")
		(rev "1.1.4")
		(comment 9 "footprints 323-326 of 379")
	)
	(layers
		(0 "F.Cu" signal)
		(4 "In1.Cu" signal)
		(6 "In2.Cu" signal)
		(8 "In3.Cu" signal)
		(10 "In4.Cu" signal)
		(12 "In5.Cu" signal)
		(14 "In6.Cu" signal)
		(2 "B.Cu" signal)
		(9 "F.Adhes" user "F.Adhesive")
		(11 "B.Adhes" user "B.Adhesive")
		(13 "F.Paste" user)
		(15 "B.Paste" user)
		(5 "F.SilkS" user "F.Silkscreen")
		(7 "B.SilkS" user "B.Silkscreen")
		(1 "F.Mask" user)
		(3 "B.Mask" user)
		(17 "Dwgs.User" user "User.Drawings")
		(19 "Cmts.User" user "User.Comments")
		(21 "Eco1.User" user "User.Eco1")
		(23 "Eco2.User" user "User.Eco2")
		(25 "Edge.Cuts" user)
		(27 "Margin" user)
		(31 "F.CrtYd" user "F.Courtyard")
		(29 "B.CrtYd" user "B.Courtyard")
		(35 "F.Fab" user)
		(33 "B.Fab" user)
	)
	(footprint "antmicro-footprints:C_0603_1608Metric"
		(layer "B.Cu")
		(at 136.55 61.86 90)
		(descr "Capacitor SMD 0603")
		(tags "capacitor 0603")
		(property "Reference" "C108"
			(at -1.19 1.58 90)
			(layer "B.SilkS")
			(effects
				(font
					(size 0.65 0.65)
					(thickness 0.15)
				)
				(justify right bottom mirror)
			)
		)
		(property "Value" "C_10u_0603"
			(at 0 -1.6 90)
			(layer "B.Fab")
			(hide yes)
			(effects
				(font
					(size 0.7 0.7)
					(thickness 0.15)
				)
				(justify right bottom mirror)
			)
		)
		(property "Datasheet" "https://www.murata.com/products/productdetail?partno=GRM188R61A106KE69%23"
			(at 0 0 90)
			(layer "F.Fab")
			(hide yes)
			(effects
				(font
					(size 1.27 1.27)
					(thickness 0.15)
				)
			)
		)
		(property "Description" "SMD Multilayer Ceramic Capacitor, 10 µF, 10 V, 0603 [1608 Metric], ± 10%, X5R, GRM Series"
			(at 0 0 90)
			(layer "F.Fab")
			(hide yes)
			(effects
				(font
					(size 1.27 1.27)
					(thickness 0.15)
				)
			)
		)
		(property "Author" "Antmicro"
			(at 198.5 -74.8 0)
			(layer "B.Fab")
			(hide yes)
			(effects
				(font
					(size 1 1)
					(thickness 0.15)
				)
				(justify mirror)
			)
		)
		(property "License" "Apache-2.0"
			(at 198.5 -74.8 0)
			(layer "B.Fab")
			(hide yes)
			(effects
				(font
					(size 1 1)
					(thickness 0.15)
				)
				(justify mirror)
			)
		)
		(property "MPN" "GRM188R61A106KE69D"
			(at 198.5 -74.8 0)
			(layer "B.Fab")
			(hide yes)
			(effects
				(font
					(size 1 1)
					(thickness 0.15)
				)
				(justify mirror)
			)
		)
		(property "Manufacturer" "Murata"
			(at 198.5 -74.8 0)
			(layer "B.Fab")
			(hide yes)
			(effects
				(font
					(size 1 1)
					(thickness 0.15)
				)
				(justify mirror)
			)
		)
		(property "Val" "10u"
			(at 198.5 -74.8 0)
			(layer "B.Fab")
			(hide yes)
			(effects
				(font
					(size 1 1)
					(thickness 0.15)
				)
				(justify mirror)
			)
		)
		(property "Voltage" ""
			(at 198.5 -74.8 0)
			(layer "B.Fab")
			(hide yes)
			(effects
				(font
					(size 1 1)
					(thickness 0.15)
				)
				(justify mirror)
			)
		)
		(property "Dielectric" "template_dielectric"
			(at 0 0 90)
			(unlocked yes)
			(layer "B.Fab")
			(hide yes)
			(effects
				(font
					(size 1 1)
					(thickness 0.15)
				)
				(justify mirror)
			)
		)
		(sheetname "/Power Supply/")
		(sheetfile "supply.kicad_sch")
		(attr smd)
		(fp_line
			(start -0.15 -0.4)
			(end 0.15 -0.4)
			(stroke
				(width 0.15)
				(type solid)
			)
			(layer "B.SilkS")
		)
		(fp_line
			(start -0.15 0.4)
			(end 0.15 0.4)
			(stroke
				(width 0.15)
				(type solid)
			)
			(layer "B.SilkS")
		)
		(fp_rect
			(start -1.25 0.65)
			(end 1.25 -0.65)
			(stroke
				(width 0.05)
				(type solid)
			)
			(fill no)
			(layer "B.CrtYd")
		)
		(fp_rect
			(start -0.8 0.4)
			(end 0.8 -0.4)
			(stroke
				(width 0.15)
				(type solid)
			)
			(fill no)
			(layer "B.Fab")
		)
		(fp_text user "License: Apache-2.0"
			(at -1.682 -5.895 270)
			(layer "B.Fab")
			(effects
				(font
					(size 0.7 0.7)
					(thickness 0.15)
				)
				(justify left bottom mirror)
			)
		)
		(fp_text user "Author: Antmicro"
			(at -1.682 -4.894 270)
			(layer "B.Fab")
			(effects
				(font
					(size 0.7 0.7)
					(thickness 0.15)
				)
				(justify left bottom mirror)
			)
		)
		(fp_text user "${REFERENCE}"
			(at -1.682 -3.895 270)
			(layer "B.Fab")
			(effects
				(font
					(size 0.7 0.7)
					(thickness 0.15)
				)
				(justify left bottom mirror)
			)
		)
		(pad "1" smd roundrect
			(at -0.7 0 90)
			(size 0.8 1)
			(layers "B.Cu" "B.Mask" "B.Paste")
			(roundrect_rratio 0.2)
			(net 1 "GND")
			(pintype "passive")
		)
		(pad "2" smd roundrect
			(at 0.7 0 90)
			(size 0.8 1)
			(layers "B.Cu" "B.Mask" "B.Paste")
			(roundrect_rratio 0.2)
			(net 2 "+3V3")
			(pintype "passive")
		)
	)
	(footprint "antmicro-footprints:TP_SMD_0.75mm"
		(layer "B.Cu")
		(at 97.69 88.95 90)
		(property "Reference" "TP30"
			(at -0.49 0.44 90)
			(layer "B.SilkS")
			(effects
				(font
					(size 0.65 0.65)
					(thickness 0.15)
				)
				(justify left bottom mirror)
			)
		)
		(property "Value" "TP_0.75mm_SMD"
			(at 0 -1.2 90)
			(layer "B.Fab")
			(hide yes)
			(effects
				(font
					(size 0.7 0.7)
					(thickness 0.15)
				)
				(justify right bottom mirror)
			)
		)
		(property "Description" "SMT test point"
			(at 0 0 90)
			(layer "F.Fab")
			(hide yes)
			(effects
				(font
					(size 1.27 1.27)
					(thickness 0.15)
				)
			)
		)
		(property "Author" "Antmicro"
			(at 186.64 -8.74 0)
			(layer "B.Fab")
			(hide yes)
			(effects
				(font
					(size 1 1)
					(thickness 0.15)
				)
				(justify mirror)
			)
		)
		(property "License" "Apache-2.0"
			(at 186.64 -8.74 0)
			(layer "B.Fab")
			(hide yes)
			(effects
				(font
					(size 1 1)
					(thickness 0.15)
				)
				(justify mirror)
			)
		)
		(property "MPN" ""
			(at 186.64 -8.74 0)
			(layer "B.Fab")
			(hide yes)
			(effects
				(font
					(size 1 1)
					(thickness 0.15)
				)
				(justify mirror)
			)
		)
		(property "Manufacturer" ""
			(at 186.64 -8.74 0)
			(layer "B.Fab")
			(hide yes)
			(effects
				(font
					(size 1 1)
					(thickness 0.15)
				)
				(justify mirror)
			)
		)
		(sheetname "/SDI/")
		(sheetfile "sdi.kicad_sch")
		(attr exclude_from_pos_files)
		(fp_circle
			(center 0 0)
			(end 0.475 0)
			(stroke
				(width 0.05)
				(type default)
			)
			(fill no)
			(layer "B.CrtYd")
		)
		(fp_text user "Author: Antmicro"
			(at -0.4 -3.901 270)
			(layer "B.Fab")
			(effects
				(font
					(size 0.7 0.7)
					(thickness 0.15)
				)
				(justify left bottom mirror)
			)
		)
		(fp_text user "License: Apache-2.0"
			(at -0.4 -5.101 270)
			(layer "B.Fab")
			(effects
				(font
					(size 0.7 0.7)
					(thickness 0.15)
				)
				(justify left bottom mirror)
			)
		)
		(fp_text user "${REFERENCE}"
			(at -0.4 -2.7 270)
			(layer "B.Fab")
			(effects
				(font
					(size 0.7 0.7)
					(thickness 0.15)
				)
				(justify left bottom mirror)
			)
		)
		(pad "1" smd circle
			(at 0 0 90)
			(size 0.75 0.75)
			(layers "B.Cu" "B.Mask")
			(net 200 "/SDI/20bit{slash}~{10bit}")
			(pinfunction "1")
			(pintype "passive")
		)
	)
	(footprint "antmicro-footprints:R_Array_4x0402"
		(layer "B.Cu")
		(at 127.06 57.44 180)
		(property "Reference" "R45"
			(at -0.97 1 0)
			(layer "B.SilkS")
			(effects
				(font
					(size 0.65 0.65)
					(thickness 0.15)
				)
				(justify left bottom mirror)
			)
		)
		(property "Value" "R_4x51R_0402_array"
			(at -1.5 -2 0)
			(layer "B.Fab")
			(hide yes)
			(effects
				(font
					(size 0.7 0.7)
					(thickness 0.15)
				)
				(justify left bottom mirror)
			)
		)
		(property "Datasheet" "http://industrial.panasonic.com/cdbs/www-data/pdf/AOC0000/AOC0000C14.pdf"
			(at 0 0 180)
			(layer "F.Fab")
			(hide yes)
			(effects
				(font
					(size 1.27 1.27)
					(thickness 0.15)
				)
			)
		)
		(property "Description" "Fixed Network Resistor, 51 ohm, Isolated, 4 Resistors, 0804 [2010 Metric], Convex, ± 5%"
			(at 0 0 180)
			(layer "F.Fab")
			(hide yes)
			(effects
				(font
					(size 1.27 1.27)
					(thickness 0.15)
				)
			)
		)
		(property "Author" "Antmicro"
			(at 254.12 114.88 0)
			(layer "B.Fab")
			(hide yes)
			(effects
				(font
					(size 1 1)
					(thickness 0.15)
				)
				(justify mirror)
			)
		)
		(property "License" "Apache-2.0"
			(at 254.12 114.88 0)
			(layer "B.Fab")
			(hide yes)
			(effects
				(font
					(size 1 1)
					(thickness 0.15)
				)
				(justify mirror)
			)
		)
		(property "MPN" "EXB28V510JX"
			(at 254.12 114.88 0)
			(layer "B.Fab")
			(hide yes)
			(effects
				(font
					(size 1 1)
					(thickness 0.15)
				)
				(justify mirror)
			)
		)
		(property "Manufacturer" "Panasonic"
			(at 254.12 114.88 0)
			(layer "B.Fab")
			(hide yes)
			(effects
				(font
					(size 1 1)
					(thickness 0.15)
				)
				(justify mirror)
			)
		)
		(property "Val" "R_4x51R_0402"
			(at 254.12 114.88 0)
			(layer "B.Fab")
			(hide yes)
			(effects
				(font
					(size 1 1)
					(thickness 0.15)
				)
				(justify mirror)
			)
		)
		(sheetname "/DDR3/")
		(sheetfile "ddr3.kicad_sch")
		(attr smd)
		(fp_line
			(start 1.167 -0.498)
			(end 1.167 0.5)
			(stroke
				(width 0.15)
				(type solid)
			)
			(layer "B.SilkS")
		)
		(fp_line
			(start -1.17 0.5)
			(end -1.17 -0.498)
			(stroke
				(width 0.15)
				(type solid)
			)
			(layer "B.SilkS")
		)
		(fp_rect
			(start -1.2 0.9)
			(end 1.2 -0.9)
			(stroke
				(width 0.05)
				(type solid)
			)
			(fill no)
			(layer "B.CrtYd")
		)
		(fp_line
			(start 0.998 0.5)
			(end 0.998 -0.498)
			(stroke
				(width 0.15)
				(type solid)
			)
			(layer "B.Fab")
		)
		(fp_line
			(start 0.998 -0.498)
			(end -1 -0.498)
			(stroke
				(width 0.15)
				(type solid)
			)
			(layer "B.Fab")
		)
		(fp_line
			(start -1 0.5)
			(end 0.998 0.5)
			(stroke
				(width 0.15)
				(type solid)
			)
			(layer "B.Fab")
		)
		(fp_line
			(start -1 -0.498)
			(end -1 0.5)
			(stroke
				(width 0.15)
				(type solid)
			)
			(layer "B.Fab")
		)
		(pad "1" smd roundrect
			(at -0.802 -0.45 180)
			(size 0.4 0.5)
			(layers "B.Cu" "B.Mask" "B.Paste")
			(roundrect_rratio 0.25)
			(net 149 "/DDR3/DDR3_A5")
			(pinfunction "R1.1")
			(pintype "passive")
		)
		(pad "2" smd roundrect
			(at -0.272 -0.45 180)
			(size 0.4 0.5)
			(layers "B.Cu" "B.Mask" "B.Paste")
			(roundrect_rratio 0.25)
			(net 150 "/DDR3/DDR3_A7")
			(pinfunction "R2.1")
			(pintype "passive")
		)
		(pad "3" smd roundrect
			(at 0.27 -0.45 180)
			(size 0.4 0.5)
			(layers "B.Cu" "B.Mask" "B.Paste")
			(roundrect_rratio 0.25)
			(net 164 "/DDR3/~{DDR3_RESET}")
			(pinfunction "R3.1")
			(pintype "passive")
		)
		(pad "4" smd roundrect
			(at 0.8 -0.45 180)
			(size 0.4 0.5)
			(layers "B.Cu" "B.Mask" "B.Paste")
			(roundrect_rratio 0.25)
			(net 153 "/DDR3/DDR3_A9")
			(pinfunction "R4.1")
			(pintype "passive")
		)
		(pad "5" smd roundrect
			(at 0.8 0.452 180)
			(size 0.4 0.5)
			(layers "B.Cu" "B.Mask" "B.Paste")
			(roundrect_rratio 0.25)
			(net 6 "Vtt")
			(pinfunction "R4.2")
			(pintype "passive")
		)
		(pad "6" smd roundrect
			(at 0.27 0.452 180)
			(size 0.4 0.5)
			(layers "B.Cu" "B.Mask" "B.Paste")
			(roundrect_rratio 0.25)
			(net 6 "Vtt")
			(pinfunction "R3.2")
			(pintype "passive")
		)
		(pad "7" smd roundrect
			(at -0.272 0.452 180)
			(size 0.4 0.5)
			(layers "B.Cu" "B.Mask" "B.Paste")
			(roundrect_rratio 0.25)
			(net 6 "Vtt")
			(pinfunction "R2.2")
			(pintype "passive")
		)
		(pad "8" smd roundrect
			(at -0.802 0.452 180)
			(size 0.4 0.5)
			(layers "B.Cu" "B.Mask" "B.Paste")
			(roundrect_rratio 0.25)
			(net 6 "Vtt")
			(pinfunction "R1.2")
			(pintype "passive")
		)
	)
	(footprint "antmicro-footprints:MSOP-8-1EP_3x3x1.1mm_P0.65mm"
		(layer "B.Cu")
		(at 133.1 59.24 -90)
		(descr "http://www.ti.com/lit/ds/symlink/tpa2005d1-q1.pdf")
		(property "Reference" "U1"
			(at -0.3 1.97 90)
			(layer "B.SilkS")
			(effects
				(font
					(size 0.65 0.65)
					(thickness 0.15)
				)
				(justify left bottom mirror)
			)
		)
		(property "Value" "MP20073DH"
			(at 7.2 -2.6 90)
			(layer "B.Fab")
			(hide yes)
			(effects
				(font
					(size 0.7 0.7)
					(thickness 0.15)
				)
				(justify left bottom mirror)
			)
		)
		(property "Datasheet" "https://www.farnell.com/datasheets/2915039.pdf"
			(at 0 0 90)
			(layer "F.Fab")
			(hide yes)
			(effects
				(font
					(size 1.27 1.27)
					(thickness 0.15)
				)
			)
		)
		(property "Description" "DDR Termination Regulator, DDR2, DDR3, 1.3V to 6V in, 2A, MSOP-EP-8"
			(at 0 0 90)
			(layer "F.Fab")
			(hide yes)
			(effects
				(font
					(size 1.27 1.27)
					(thickness 0.15)
				)
			)
		)
		(property "Author" "Antmicro"
			(at 73.86 192.34 0)
			(layer "B.Fab")
			(hide yes)
			(effects
				(font
					(size 1 1)
					(thickness 0.15)
				)
				(justify mirror)
			)
		)
		(property "License" "Apache-2.0"
			(at 73.86 192.34 0)
			(layer "B.Fab")
			(hide yes)
			(effects
				(font
					(size 1 1)
					(thickness 0.15)
				)
				(justify mirror)
			)
		)
		(property "MPN" "MP20073DH-LF-P"
			(at 73.86 192.34 0)
			(layer "B.Fab")
			(hide yes)
			(effects
				(font
					(size 1 1)
					(thickness 0.15)
				)
				(justify mirror)
			)
		)
		(property "Manufacturer" "Monolithic Power Systems"
			(at 73.86 192.34 0)
			(layer "B.Fab")
			(hide yes)
			(effects
				(font
					(size 1 1)
					(thickness 0.15)
				)
				(justify mirror)
			)
		)
		(sheetname "/Power Supply/")
		(sheetfile "supply.kicad_sch")
		(attr smd)
		(fp_line
			(start -1.299 1.601)
			(end -1.6 1.302)
			(stroke
				(width 0.15)
				(type solid)
			)
			(layer "B.SilkS")
		)
		(fp_line
			(start 1.3 1.601)
			(end 1.601 1.601)
			(stroke
				(width 0.15)
				(type solid)
			)
			(layer "B.SilkS")
		)
		(fp_line
			(start 1.601 1.601)
			(end 1.601 1.302)
			(stroke
				(width 0.15)
				(type solid)
			)
			(layer "B.SilkS")
		)
		(fp_line
			(start 1.601 -1.298)
			(end 1.601 -1.6)
			(stroke
				(width 0.15)
				(type solid)
			)
			(layer "B.SilkS")
		)
		(fp_line
			(start -1.6 -1.6)
			(end -1.6 -1.298)
			(stroke
				(width 0.15)
				(type solid)
			)
			(layer "B.SilkS")
		)
		(fp_line
			(start -1.299 -1.6)
			(end -1.6 -1.6)
			(stroke
				(width 0.15)
				(type solid)
			)
			(layer "B.SilkS")
		)
		(fp_line
			(start 1.601 -1.6)
			(end 1.3 -1.6)
			(stroke
				(width 0.15)
				(type solid)
			)
			(layer "B.SilkS")
		)
		(fp_circle
			(center -2.1 1.4)
			(end -2.15 1.45)
			(stroke
				(width 0.15)
				(type solid)
			)
			(fill yes)
			(layer "B.SilkS")
		)
		(fp_rect
			(start -3.179 1.747)
			(end 3.171 -1.753)
			(stroke
				(width 0.05)
				(type solid)
			)
			(fill no)
			(layer "B.CrtYd")
		)
		(fp_line
			(start -1.099 1.451)
			(end -1.45 1.101)
			(stroke
				(width 0.15)
				(type solid)
			)
			(layer "B.Fab")
		)
		(fp_line
			(start 1.45 1.451)
			(end -1.099 1.451)
			(stroke
				(width 0.15)
				(type solid)
			)
			(layer "B.Fab")
		)
		(fp_line
			(start 1.45 1.451)
			(end 1.45 -1.449)
			(stroke
				(width 0.15)
				(type solid)
			)
			(layer "B.Fab")
		)
		(fp_line
			(start -1.45 1.101)
			(end -1.45 -1.449)
			(stroke
				(width 0.15)
				(type solid)
			)
			(layer "B.Fab")
		)
		(fp_line
			(start 1.45 -1.449)
			(end -1.45 -1.449)
			(stroke
				(width 0.15)
				(type solid)
			)
			(layer "B.Fab")
		)
		(fp_text user "${REFERENCE}"
			(at -3.179 -4.6 90)
			(layer "B.Fab")
			(effects
				(font
					(size 0.7 0.7)
					(thickness 0.15)
				)
				(justify left bottom mirror)
			)
		)
		(fp_text user "Author: Antmicro"
			(at -3.179 -5.8 90)
			(layer "B.Fab")
			(effects
				(font
					(size 0.7 0.7)
					(thickness 0.15)
				)
				(justify left bottom mirror)
			)
		)
		(fp_text user "License: Apache-2.0"
			(at -3.179 -7 90)
			(layer "B.Fab")
			(effects
				(font
					(size 0.7 0.7)
					(thickness 0.15)
				)
				(justify left bottom mirror)
			)
		)
		(pad "1" smd roundrect
			(at -2.199 0.977)
			(size 0.45 1.45)
			(layers "B.Cu" "B.Mask" "B.Paste")
			(roundrect_rratio 0.25)
			(net 60 "Net-(U1-DDQ)")
			(pinfunction "DDQ")
			(pintype "power_in")
		)
		(pad "2" smd roundrect
			(at -2.199 0.326)
			(size 0.45 1.45)
			(layers "B.Cu" "B.Mask" "B.Paste")
			(roundrect_rratio 0.25)
			(net 6 "Vtt")
			(pinfunction "V_{TT}")
			(pintype "passive")
		)
		(pad "3" smd roundrect
			(at -2.199 -0.324)
			(size 0.45 1.45)
			(layers "B.Cu" "B.Mask" "B.Paste")
			(roundrect_rratio 0.25)
			(net 1 "GND")
			(pinfunction "GND")
			(pintype "power_in")
		)
		(pad "4" smd roundrect
			(at -2.199 -0.973)
			(size 0.45 1.45)
			(layers "B.Cu" "B.Mask" "B.Paste")
			(roundrect_rratio 0.25)
			(net 6 "Vtt")
			(pinfunction "V_{TTSEN}")
			(pintype "passive")
		)
		(pad "5" smd roundrect
			(at 2.201 -0.973)
			(size 0.45 1.45)
			(layers "B.Cu" "B.Mask" "B.Paste")
			(roundrect_rratio 0.25)
			(net 2 "+3V3")
			(pinfunction "V_{DRV}")
			(pintype "passive")
		)
		(pad "6" smd roundrect
			(at 2.201 -0.324)
			(size 0.45 1.45)
			(layers "B.Cu" "B.Mask" "B.Paste")
			(roundrect_rratio 0.25)
			(net 30 "Net-(U1-REF)")
			(pinfunction "REF")
			(pintype "passive")
		)
		(pad "7" smd roundrect
			(at 2.201 0.326)
			(size 0.45 1.45)
			(layers "B.Cu" "B.Mask" "B.Paste")
			(roundrect_rratio 0.25)
			(net 262 "Net-(U1-V_{TT_EN})")
			(pinfunction "V_{TT_EN}")
			(pintype "passive")
		)
		(pad "8" smd roundrect
			(at 2.201 0.977)
			(size 0.45 1.45)
			(layers "B.Cu" "B.Mask" "B.Paste")
			(roundrect_rratio 0.25)
			(net 5 "Vref")
			(pinfunction "V_{TTREF}")
			(pintype "passive")
		)
		(pad "9" smd rect
			(at 0 0 270)
			(size 1.98 1.88)
			(layers "B.Cu" "B.Mask" "B.Paste")
			(net 1 "GND")
			(pinfunction "GND")
			(pintype "passive")
		)
	)
)
